(kicad_pcb
	(version 20260206)
	(generator "pcbnew")
	(generator_version "10.0")
	(general
		(thickness 1.6)
		(legacy_teardrops no)
	)
	(paper "A4")
	(title_block
		(title "01162023_DA0F0TEBIF0_F0T_Expander_BD_F_brd_V02_OCP.brd")
		(comment 1 "Grand Teton / footprints 1807-1814 of 9728")
	)
	(layers
		(0 "F.Cu" signal "TOP")
		(4 "In1.Cu" signal "GND")
		(6 "In2.Cu" signal "VCC")
		(8 "In3.Cu" signal "VCC1")
		(10 "In4.Cu" signal "GND1")
		(12 "In5.Cu" signal "IN1")
		(14 "In6.Cu" signal "GND2")
		(16 "In7.Cu" signal "IN2")
		(18 "In8.Cu" signal "GND3")
		(20 "In9.Cu" signal "IN3")
		(22 "In10.Cu" signal "GND4")
		(24 "In11.Cu" signal "IN4")
		(26 "In12.Cu" signal "GND5")
		(28 "In13.Cu" signal "IN5")
		(30 "In14.Cu" signal "GND6")
		(32 "In15.Cu" signal "IN6")
		(34 "In16.Cu" signal "GND7")
		(2 "B.Cu" signal "BOTTOM")
		(9 "F.Adhes" user "F.Adhesive")
		(11 "B.Adhes" user "B.Adhesive")
		(13 "F.Paste" user "Package Geometry/Pastemask Top")
		(15 "B.Paste" user "Package Geometry/Pastemask Bottom")
		(5 "F.SilkS" user "Ref Des/Silkscreen Top")
		(7 "B.SilkS" user "Ref Des/Silkscreen Bottom")
		(1 "F.Mask" user "Board Geometry/Soldermask Top")
		(3 "B.Mask" user "Board Geometry/Soldermask Bottom")
		(17 "Dwgs.User" user "User.Drawings")
		(19 "Cmts.User" user "User.Comments")
		(21 "Eco1.User" user "User.Eco1")
		(23 "Eco2.User" user "User.Eco2")
		(25 "Edge.Cuts" user "Board Geometry/Outline")
		(27 "Margin" user)
		(31 "F.CrtYd" user "Package Geometry/Place Bound Top")
		(29 "B.CrtYd" user "Package Geometry/Place Bound Bottom")
		(35 "F.Fab" user "Ref Des/Assembly Top")
		(33 "B.Fab" user "Ref Des/Assembly Bottom")
	)
	(footprint ""
		(layer "F.Cu")
		(at 133.892544 -31.825184 180)
		(property "Reference" "C279"
			(at 0 0 180)
			(layer "F.SilkS")
			(hide yes)
			(effects
				(font
					(size 1.27 1.27)
				)
			)
		)
		(property "Value" ""
			(at 0 0 180)
			(layer "F.Fab")
			(effects
				(font
					(size 1.27 1.27)
				)
			)
		)
		(duplicate_pad_numbers_are_jumpers no)
		(fp_line
			(start 0.299974 0.150114)
			(end -0.299974 0.150114)
			(stroke
				(width 0.1)
				(type default)
			)
			(layer "F.Fab")
		)
		(fp_line
			(start 0.299974 -0.150114)
			(end 0.299974 0.150114)
			(stroke
				(width 0.1)
				(type default)
			)
			(layer "F.Fab")
		)
		(fp_line
			(start -0.299974 0.150114)
			(end -0.299974 -0.150114)
			(stroke
				(width 0.1)
				(type default)
			)
			(layer "F.Fab")
		)
		(fp_line
			(start -0.299974 -0.150114)
			(end 0.299974 -0.150114)
			(stroke
				(width 0.1)
				(type default)
			)
			(layer "F.Fab")
		)
		(pad "1" smd rect
			(at -0.2667 0 180)
			(size 0.3048 0.381)
			(layers "F.Cu" "F.Mask" "F.Paste")
			(net "P5E_PEX1_STN2_TX_DN<46>")
		)
		(pad "2" smd rect
			(at 0.2667 0 180)
			(size 0.3048 0.381)
			(layers "F.Cu" "F.Mask" "F.Paste")
			(net "P5E_PEX1_STN2_TX_C_DN<46>")
		)
	)
	(footprint ""
		(layer "F.Cu")
		(at 323.476112 -297.46448 180)
		(property "Reference" "R3988"
			(at 0 0 180)
			(layer "F.SilkS")
			(hide yes)
			(effects
				(font
					(size 1.27 1.27)
				)
			)
		)
		(property "Value" ""
			(at 0 0 180)
			(layer "F.Fab")
			(effects
				(font
					(size 1.27 1.27)
				)
			)
		)
		(duplicate_pad_numbers_are_jumpers no)
		(fp_line
			(start 0.7874 0.4064)
			(end -0.7874 0.4064)
			(stroke
				(width 0.1524)
				(type default)
			)
			(layer "F.SilkS")
		)
		(fp_line
			(start 0.7874 -0.4064)
			(end 0.7874 0.4064)
			(stroke
				(width 0.1524)
				(type default)
			)
			(layer "F.SilkS")
		)
		(fp_line
			(start -0.7874 0.4064)
			(end -0.7874 -0.4064)
			(stroke
				(width 0.1524)
				(type default)
			)
			(layer "F.SilkS")
		)
		(fp_line
			(start -0.7874 -0.4064)
			(end 0.7874 -0.4064)
			(stroke
				(width 0.1524)
				(type default)
			)
			(layer "F.SilkS")
		)
		(fp_line
			(start 0.67945 0.3048)
			(end 0.120396 0.3048)
			(stroke
				(width 0.1)
				(type default)
			)
			(layer "F.Fab")
		)
		(fp_line
			(start 0.67945 -0.3048)
			(end 0.67945 0.3048)
			(stroke
				(width 0.1)
				(type default)
			)
			(layer "F.Fab")
		)
		(fp_line
			(start 0.12065 -0.2794)
			(end 0.12065 -0.3048)
			(stroke
				(width 0.1)
				(type default)
			)
			(layer "F.Fab")
		)
		(fp_line
			(start 0.12065 -0.3048)
			(end 0.67945 -0.3048)
			(stroke
				(width 0.1)
				(type default)
			)
			(layer "F.Fab")
		)
		(fp_line
			(start 0.120396 0.3048)
			(end 0.120396 0.2794)
			(stroke
				(width 0.1)
				(type default)
			)
			(layer "F.Fab")
		)
		(fp_line
			(start 0.120396 0.2794)
			(end -0.12065 0.2794)
			(stroke
				(width 0.1)
				(type default)
			)
			(layer "F.Fab")
		)
		(fp_line
			(start -0.12065 0.3048)
			(end -0.67945 0.3048)
			(stroke
				(width 0.1)
				(type default)
			)
			(layer "F.Fab")
		)
		(fp_line
			(start -0.12065 0.2794)
			(end -0.12065 0.3048)
			(stroke
				(width 0.1)
				(type default)
			)
			(layer "F.Fab")
		)
		(fp_line
			(start -0.12065 -0.2794)
			(end 0.12065 -0.2794)
			(stroke
				(width 0.1)
				(type default)
			)
			(layer "F.Fab")
		)
		(fp_line
			(start -0.12065 -0.305054)
			(end -0.12065 -0.2794)
			(stroke
				(width 0.1)
				(type default)
			)
			(layer "F.Fab")
		)
		(fp_line
			(start -0.67945 0.3048)
			(end -0.67945 -0.305054)
			(stroke
				(width 0.1)
				(type default)
			)
			(layer "F.Fab")
		)
		(fp_line
			(start -0.67945 -0.305054)
			(end -0.12065 -0.305054)
			(stroke
				(width 0.1)
				(type default)
			)
			(layer "F.Fab")
		)
		(pad "1" smd circle
			(at -0.40005 0 180)
			(size 0 0)
			(layers "F.Cu" "F.Mask" "F.Paste")
			(net "SMB_PEX2_HOST_LS_SCL")
		)
		(pad "2" smd circle
			(at 0.40005 0 180)
			(size 0 0)
			(layers "F.Cu" "F.Mask" "F.Paste")
			(net "I2C_PEX2_HOST_R_SCL")
		)
	)
	(footprint ""
		(layer "F.Cu")
		(at 374.27154 -343.952322 90)
		(property "Reference" "C780"
			(at 0 0 90)
			(layer "F.SilkS")
			(hide yes)
			(effects
				(font
					(size 1.27 1.27)
				)
			)
		)
		(property "Value" ""
			(at 0 0 90)
			(layer "F.Fab")
			(effects
				(font
					(size 1.27 1.27)
				)
			)
		)
		(duplicate_pad_numbers_are_jumpers no)
		(fp_line
			(start 0.299974 -0.150114)
			(end 0.299974 0.150114)
			(stroke
				(width 0.1)
				(type default)
			)
			(layer "F.Fab")
		)
		(fp_line
			(start -0.299974 -0.150114)
			(end 0.299974 -0.150114)
			(stroke
				(width 0.1)
				(type default)
			)
			(layer "F.Fab")
		)
		(fp_line
			(start 0.299974 0.150114)
			(end -0.299974 0.150114)
			(stroke
				(width 0.1)
				(type default)
			)
			(layer "F.Fab")
		)
		(fp_line
			(start -0.299974 0.150114)
			(end -0.299974 -0.150114)
			(stroke
				(width 0.1)
				(type default)
			)
			(layer "F.Fab")
		)
		(pad "1" smd rect
			(at -0.2667 0 90)
			(size 0.3048 0.381)
			(layers "F.Cu" "F.Mask" "F.Paste")
			(net "P5E_PEX3_STN6_TX_DP<102>")
		)
		(pad "2" smd rect
			(at 0.2667 0 90)
			(size 0.3048 0.381)
			(layers "F.Cu" "F.Mask" "F.Paste")
			(net "P5E_PEX3_STN6_TX_C_DP<102>")
		)
	)
	(footprint ""
		(layer "F.Cu")
		(at 327.533 -212.217)
		(property "Reference" "R4158"
			(at 0 0 0)
			(layer "F.SilkS")
			(hide yes)
			(effects
				(font
					(size 1.27 1.27)
				)
			)
		)
		(property "Value" ""
			(at 0 0 0)
			(layer "F.Fab")
			(effects
				(font
					(size 1.27 1.27)
				)
			)
		)
		(duplicate_pad_numbers_are_jumpers no)
		(fp_line
			(start -0.7874 -0.4064)
			(end 0.7874 -0.4064)
			(stroke
				(width 0.1524)
				(type default)
			)
			(layer "F.SilkS")
		)
		(fp_line
			(start -0.7874 0.4064)
			(end -0.7874 -0.4064)
			(stroke
				(width 0.1524)
				(type default)
			)
			(layer "F.SilkS")
		)
		(fp_line
			(start 0.7874 -0.4064)
			(end 0.7874 0.4064)
			(stroke
				(width 0.1524)
				(type default)
			)
			(layer "F.SilkS")
		)
		(fp_line
			(start 0.7874 0.4064)
			(end -0.7874 0.4064)
			(stroke
				(width 0.1524)
				(type default)
			)
			(layer "F.SilkS")
		)
		(fp_line
			(start -0.67945 -0.305054)
			(end -0.12065 -0.305054)
			(stroke
				(width 0.1)
				(type default)
			)
			(layer "F.Fab")
		)
		(fp_line
			(start -0.67945 0.3048)
			(end -0.67945 -0.305054)
			(stroke
				(width 0.1)
				(type default)
			)
			(layer "F.Fab")
		)
		(fp_line
			(start -0.12065 -0.305054)
			(end -0.12065 -0.2794)
			(stroke
				(width 0.1)
				(type default)
			)
			(layer "F.Fab")
		)
		(fp_line
			(start -0.12065 -0.2794)
			(end 0.12065 -0.2794)
			(stroke
				(width 0.1)
				(type default)
			)
			(layer "F.Fab")
		)
		(fp_line
			(start -0.12065 0.2794)
			(end -0.12065 0.3048)
			(stroke
				(width 0.1)
				(type default)
			)
			(layer "F.Fab")
		)
		(fp_line
			(start -0.12065 0.3048)
			(end -0.67945 0.3048)
			(stroke
				(width 0.1)
				(type default)
			)
			(layer "F.Fab")
		)
		(fp_line
			(start 0.120396 0.2794)
			(end -0.12065 0.2794)
			(stroke
				(width 0.1)
				(type default)
			)
			(layer "F.Fab")
		)
		(fp_line
			(start 0.120396 0.3048)
			(end 0.120396 0.2794)
			(stroke
				(width 0.1)
				(type default)
			)
			(layer "F.Fab")
		)
		(fp_line
			(start 0.12065 -0.3048)
			(end 0.67945 -0.3048)
			(stroke
				(width 0.1)
				(type default)
			)
			(layer "F.Fab")
		)
		(fp_line
			(start 0.12065 -0.2794)
			(end 0.12065 -0.3048)
			(stroke
				(width 0.1)
				(type default)
			)
			(layer "F.Fab")
		)
		(fp_line
			(start 0.67945 -0.3048)
			(end 0.67945 0.3048)
			(stroke
				(width 0.1)
				(type default)
			)
			(layer "F.Fab")
		)
		(fp_line
			(start 0.67945 0.3048)
			(end 0.120396 0.3048)
			(stroke
				(width 0.1)
				(type default)
			)
			(layer "F.Fab")
		)
		(pad "1" smd circle
			(at -0.40005 0)
			(size 0 0)
			(layers "F.Cu" "F.Mask" "F.Paste")
			(net "PRSNT_SSD11_FPGA_R_N")
		)
		(pad "2" smd circle
			(at 0.40005 0)
			(size 0 0)
			(layers "F.Cu" "F.Mask" "F.Paste")
			(net "PRSNT_SSD11_FPGA_N")
		)
	)
	(footprint ""
		(layer "F.Cu")
		(at 451.622668 -258.331208 -90)
		(property "Reference" "R6562"
			(at 0 0 270)
			(layer "F.SilkS")
			(hide yes)
			(effects
				(font
					(size 1.27 1.27)
				)
			)
		)
		(property "Value" ""
			(at 0 0 270)
			(layer "F.Fab")
			(effects
				(font
					(size 1.27 1.27)
				)
			)
		)
		(duplicate_pad_numbers_are_jumpers no)
		(fp_line
			(start -0.7874 0.4064)
			(end -0.7874 -0.4064)
			(stroke
				(width 0.1524)
				(type default)
			)
			(layer "F.SilkS")
		)
		(fp_line
			(start 0.7874 0.4064)
			(end -0.7874 0.4064)
			(stroke
				(width 0.1524)
				(type default)
			)
			(layer "F.SilkS")
		)
		(fp_line
			(start -0.7874 -0.4064)
			(end 0.7874 -0.4064)
			(stroke
				(width 0.1524)
				(type default)
			)
			(layer "F.SilkS")
		)
		(fp_line
			(start 0.7874 -0.4064)
			(end 0.7874 0.4064)
			(stroke
				(width 0.1524)
				(type default)
			)
			(layer "F.SilkS")
		)
		(fp_line
			(start -0.67945 0.3048)
			(end -0.67945 -0.305054)
			(stroke
				(width 0.1)
				(type default)
			)
			(layer "F.Fab")
		)
		(fp_line
			(start -0.12065 0.3048)
			(end -0.67945 0.3048)
			(stroke
				(width 0.1)
				(type default)
			)
			(layer "F.Fab")
		)
		(fp_line
			(start 0.120396 0.3048)
			(end 0.120396 0.2794)
			(stroke
				(width 0.1)
				(type default)
			)
			(layer "F.Fab")
		)
		(fp_line
			(start 0.67945 0.3048)
			(end 0.120396 0.3048)
			(stroke
				(width 0.1)
				(type default)
			)
			(layer "F.Fab")
		)
		(fp_line
			(start -0.12065 0.2794)
			(end -0.12065 0.3048)
			(stroke
				(width 0.1)
				(type default)
			)
			(layer "F.Fab")
		)
		(fp_line
			(start 0.120396 0.2794)
			(end -0.12065 0.2794)
			(stroke
				(width 0.1)
				(type default)
			)
			(layer "F.Fab")
		)
		(fp_line
			(start -0.12065 -0.2794)
			(end 0.12065 -0.2794)
			(stroke
				(width 0.1)
				(type default)
			)
			(layer "F.Fab")
		)
		(fp_line
			(start 0.12065 -0.2794)
			(end 0.12065 -0.3048)
			(stroke
				(width 0.1)
				(type default)
			)
			(layer "F.Fab")
		)
		(fp_line
			(start 0.12065 -0.3048)
			(end 0.67945 -0.3048)
			(stroke
				(width 0.1)
				(type default)
			)
			(layer "F.Fab")
		)
		(fp_line
			(start 0.67945 -0.3048)
			(end 0.67945 0.3048)
			(stroke
				(width 0.1)
				(type default)
			)
			(layer "F.Fab")
		)
		(fp_line
			(start -0.67945 -0.305054)
			(end -0.12065 -0.305054)
			(stroke
				(width 0.1)
				(type default)
			)
			(layer "F.Fab")
		)
		(fp_line
			(start -0.12065 -0.305054)
			(end -0.12065 -0.2794)
			(stroke
				(width 0.1)
				(type default)
			)
			(layer "F.Fab")
		)
		(pad "1" smd circle
			(at -0.40005 0 270)
			(size 0 0)
			(layers "F.Cu" "F.Mask" "F.Paste")
			(net "P1V25_SERDES_VDDPLL_PEX3")
		)
		(pad "2" smd circle
			(at 0.40005 0 270)
			(size 0 0)
			(layers "F.Cu" "F.Mask" "F.Paste")
			(net "P1V25_SERDES_VDDPLL_PEX3_C9")
		)
	)
	(footprint ""
		(layer "F.Cu")
		(at 319.609724 -343.952322 90)
		(property "Reference" "C556"
			(at 0 0 90)
			(layer "F.SilkS")
			(hide yes)
			(effects
				(font
					(size 1.27 1.27)
				)
			)
		)
		(property "Value" ""
			(at 0 0 90)
			(layer "F.Fab")
			(effects
				(font
					(size 1.27 1.27)
				)
			)
		)
		(duplicate_pad_numbers_are_jumpers no)
		(fp_line
			(start 0.299974 -0.150114)
			(end 0.299974 0.150114)
			(stroke
				(width 0.1)
				(type default)
			)
			(layer "F.Fab")
		)
		(fp_line
			(start -0.299974 -0.150114)
			(end 0.299974 -0.150114)
			(stroke
				(width 0.1)
				(type default)
			)
			(layer "F.Fab")
		)
		(fp_line
			(start 0.299974 0.150114)
			(end -0.299974 0.150114)
			(stroke
				(width 0.1)
				(type default)
			)
			(layer "F.Fab")
		)
		(fp_line
			(start -0.299974 0.150114)
			(end -0.299974 -0.150114)
			(stroke
				(width 0.1)
				(type default)
			)
			(layer "F.Fab")
		)
		(pad "1" smd rect
			(at -0.2667 0 90)
			(size 0.3048 0.381)
			(layers "F.Cu" "F.Mask" "F.Paste")
			(net "P5E_PEX2_STN6_TX_DN<109>")
		)
		(pad "2" smd rect
			(at 0.2667 0 90)
			(size 0.3048 0.381)
			(layers "F.Cu" "F.Mask" "F.Paste")
			(net "P5E_PEX2_STN6_TX_C_DN<109>")
		)
	)
	(footprint ""
		(layer "F.Cu")
		(at 26.374344 -250.070874 -90)
		(property "Reference" "R1154"
			(at 0 0 270)
			(layer "F.SilkS")
			(hide yes)
			(effects
				(font
					(size 1.27 1.27)
				)
			)
		)
		(property "Value" ""
			(at 0 0 270)
			(layer "F.Fab")
			(effects
				(font
					(size 1.27 1.27)
				)
			)
		)
		(duplicate_pad_numbers_are_jumpers no)
		(fp_line
			(start -0.7874 0.4064)
			(end -0.7874 -0.4064)
			(stroke
				(width 0.1524)
				(type default)
			)
			(layer "F.SilkS")
		)
		(fp_line
			(start 0.7874 0.4064)
			(end -0.7874 0.4064)
			(stroke
				(width 0.1524)
				(type default)
			)
			(layer "F.SilkS")
		)
		(fp_line
			(start -0.7874 -0.4064)
			(end 0.7874 -0.4064)
			(stroke
				(width 0.1524)
				(type default)
			)
			(layer "F.SilkS")
		)
		(fp_line
			(start 0.7874 -0.4064)
			(end 0.7874 0.4064)
			(stroke
				(width 0.1524)
				(type default)
			)
			(layer "F.SilkS")
		)
		(fp_line
			(start -0.67945 0.3048)
			(end -0.67945 -0.305054)
			(stroke
				(width 0.1)
				(type default)
			)
			(layer "F.Fab")
		)
		(fp_line
			(start -0.12065 0.3048)
			(end -0.67945 0.3048)
			(stroke
				(width 0.1)
				(type default)
			)
			(layer "F.Fab")
		)
		(fp_line
			(start 0.120396 0.3048)
			(end 0.120396 0.2794)
			(stroke
				(width 0.1)
				(type default)
			)
			(layer "F.Fab")
		)
		(fp_line
			(start 0.67945 0.3048)
			(end 0.120396 0.3048)
			(stroke
				(width 0.1)
				(type default)
			)
			(layer "F.Fab")
		)
		(fp_line
			(start -0.12065 0.2794)
			(end -0.12065 0.3048)
			(stroke
				(width 0.1)
				(type default)
			)
			(layer "F.Fab")
		)
		(fp_line
			(start 0.120396 0.2794)
			(end -0.12065 0.2794)
			(stroke
				(width 0.1)
				(type default)
			)
			(layer "F.Fab")
		)
		(fp_line
			(start -0.12065 -0.2794)
			(end 0.12065 -0.2794)
			(stroke
				(width 0.1)
				(type default)
			)
			(layer "F.Fab")
		)
		(fp_line
			(start 0.12065 -0.2794)
			(end 0.12065 -0.3048)
			(stroke
				(width 0.1)
				(type default)
			)
			(layer "F.Fab")
		)
		(fp_line
			(start 0.12065 -0.3048)
			(end 0.67945 -0.3048)
			(stroke
				(width 0.1)
				(type default)
			)
			(layer "F.Fab")
		)
		(fp_line
			(start 0.67945 -0.3048)
			(end 0.67945 0.3048)
			(stroke
				(width 0.1)
				(type default)
			)
			(layer "F.Fab")
		)
		(fp_line
			(start -0.67945 -0.305054)
			(end -0.12065 -0.305054)
			(stroke
				(width 0.1)
				(type default)
			)
			(layer "F.Fab")
		)
		(fp_line
			(start -0.12065 -0.305054)
			(end -0.12065 -0.2794)
			(stroke
				(width 0.1)
				(type default)
			)
			(layer "F.Fab")
		)
		(pad "1" smd circle
			(at -0.40005 0 270)
			(size 0 0)
			(layers "F.Cu" "F.Mask" "F.Paste")
			(net "PEX0_MODE_SEL2")
		)
		(pad "2" smd circle
			(at 0.40005 0 270)
			(size 0 0)
			(layers "F.Cu" "F.Mask" "F.Paste")
			(net "P1V8_PEX")
		)
	)
	(footprint ""
		(layer "F.Cu")
		(at 491.81893 -526.883122)
		(property "Reference" "J4_23"
			(at -0.5842 -1.31953 0)
			(unlocked yes)
			(layer "B.SilkS")
			(effects
				(font
					(size 0.7874 0.5842)
					(thickness 0.1524)
				)
				(justify left mirror)
			)
		)
		(property "Value" ""
			(at 0 0 0)
			(layer "F.Fab")
			(effects
				(font
					(size 1.27 1.27)
				)
			)
		)
		(duplicate_pad_numbers_are_jumpers no)
		(pad "1" thru_hole circle
			(at 0 0)
			(size 0.4572 0.4572)
			(drill 0.2032)
			(layers "*.Cu" "*.Mask")
			(remove_unused_layers no)
			(net "Net_9329")
			(clearance 0.127)
			(thermal_gap 0.127)
			(padstack
				(mode front_inner_back)
				(layer "Inner"
					(shape circle)
					(size 0.4572 0.4572)
					(clearance 0.127)
				)
				(layer "B.Cu"
					(shape circle)
					(size 0.508 0.508)
					(clearance 0.1016)
				)
			)
		)
	)
)
